FILE_TYPE = MULTI_PHYS_TABLE;

PART 'FCONN168_ME1016810202011_SCM'

{========================================================================================}
:VALUE                          | PART_TYPE | MATERIAL | PART_NUMBER    = STANDARD | LIFECYCLE | PART_NUMBER | JEDEC_TYPE                  | ALT_SYMBOLS | DESCRIPTION                     | MANUFTR | MANUF_PN | RD_CMPLS_LVL | CMPLS_LVL | CLASS | DIP_SMD | FROM_PJ    | DATA                      | FP_ECN                          | EE_CHECK_LIST | STATUS | PSL | PREFERENCE | CREATOR | CREATEDAY  | ESD_CDM | ESD_HBM | ESD_MM | MSD | PIN_LENGTH_LONG_PIN | PIN_LENGTH_SHORT_PIN ;
{========================================================================================}
 'FCONN168_ME1016810202011_SCM' | 'SMLF'    | 'EMPTY'  | 'GOLD244'(!)   = ''       | ''        | 'GOLD244'   |'GOLD_168P_ME1016813401311'| ''          | 'GOLD_168P_ME1016810202011_SCM' | 'APL'   | ''       | ''           | ''        | 'IO'  | ''      | 'F0T-IVES' | 'APL_ME1016810202011.pdf' | 'GOLD_168P_ME1016810202011.msg' | ''            | ''     | ''  | ''         | ''      | '20211108' | ''      | ''      | ''     | ''  | ''                  | ''                  

END_PART

END.

